(kicad_pcb
	(version 20260206)
	(generator "pcbnew")
	(generator_version "10.0")
	(general
		(thickness 1.6)
		(legacy_teardrops no)
	)
	(paper "A4")
	(title_block
		(title "04192023_DAF0TMB3IC0_F0TG_MB_C_brd_V02_OCP.brd")
		(comment 1 "Grand Teton / footprint 2783 of 8354 (U26), pads 1427-1538 of 6102")
	)
	(layers
		(0 "F.Cu" signal "TOP")
		(4 "In1.Cu" signal "GND")
		(6 "In2.Cu" signal "IN1")
		(8 "In3.Cu" signal "GND1")
		(10 "In4.Cu" signal "IN2")
		(12 "In5.Cu" signal "GND2")
		(14 "In6.Cu" signal "IN3")
		(16 "In7.Cu" signal "GND3")
		(18 "In8.Cu" signal "VCC")
		(20 "In9.Cu" signal "VCC1")
		(22 "In10.Cu" signal "GND4")
		(24 "In11.Cu" signal "IN4")
		(26 "In12.Cu" signal "GND5")
		(28 "In13.Cu" signal "IN5")
		(30 "In14.Cu" signal "GND6")
		(32 "In15.Cu" signal "IN6")
		(34 "In16.Cu" signal "GND7")
		(2 "B.Cu" signal "BOTTOM")
		(9 "F.Adhes" user "F.Adhesive")
		(11 "B.Adhes" user "B.Adhesive")
		(13 "F.Paste" user "Package Geometry/Pastemask Top")
		(15 "B.Paste" user "Package Geometry/Pastemask Bottom")
		(5 "F.SilkS" user "Ref Des/Silkscreen Top")
		(7 "B.SilkS" user "Ref Des/Silkscreen Bottom")
		(1 "F.Mask" user "Board Geometry/Soldermask Top")
		(3 "B.Mask" user "Board Geometry/Soldermask Bottom")
		(17 "Dwgs.User" user "User.Drawings")
		(19 "Cmts.User" user "User.Comments")
		(21 "Eco1.User" user "User.Eco1")
		(23 "Eco2.User" user "User.Eco2")
		(25 "Edge.Cuts" user "Board Geometry/Outline")
		(27 "Margin" user)
		(31 "F.CrtYd" user "Package Geometry/Place Bound Top")
		(29 "B.CrtYd" user "Package Geometry/Place Bound Bottom")
		(35 "F.Fab" user "Ref Des/Assembly Top")
		(33 "B.Fab" user "Ref Des/Assembly Bottom")
	)
	(footprint ""
		(layer "F.Cu")
		(at 111.927894 -258.880356 180)
		(property "Reference" "U26"
			(at -45.05579 -61.794136 0)
			(unlocked yes)
			(layer "F.SilkS")
			(effects
				(font
					(size 0.7874 0.5842)
					(thickness 0.1524)
				)
			)
		)
		(property "Value" ""
			(at 0 0 180)
			(layer "F.Fab")
			(effects
				(font
					(size 1.27 1.27)
				)
			)
		)
		(duplicate_pad_numbers_are_jumpers no)
		(pad "AY14" smd circle
			(at -22.409912 -5.219954 180)
			(size 0.450088 0.450088)
			(layers "F.Cu" "F.Mask" "F.Paste")
			(net "M_H_CPU1_SA_CA<2>")
		)
		(pad "AY15" smd circle
			(at -21.470112 -5.219954 180)
			(size 0.450088 0.450088)
			(layers "F.Cu" "F.Mask" "F.Paste")
			(net "GND")
		)
		(pad "AY16" smd circle
			(at -20.530058 -5.219954 180)
			(size 0.450088 0.450088)
			(layers "F.Cu" "F.Mask" "F.Paste")
			(net "M_J_CPU1_SA_CA<1>")
		)
		(pad "AY17" smd circle
			(at -19.590004 -5.219954 180)
			(size 0.450088 0.450088)
			(layers "F.Cu" "F.Mask" "F.Paste")
			(net "GND")
		)
		(pad "AY18" smd circle
			(at -18.64995 -5.219954 180)
			(size 0.450088 0.450088)
			(layers "F.Cu" "F.Mask" "F.Paste")
			(net "M_J_CPU1_SA_CA<2>")
		)
		(pad "AY19" smd circle
			(at -17.709896 -5.219954 180)
			(size 0.450088 0.450088)
			(layers "F.Cu" "F.Mask" "F.Paste")
			(net "GND")
		)
		(pad "AY20" smd circle
			(at -16.770096 -5.219954 180)
			(size 0.450088 0.450088)
			(layers "F.Cu" "F.Mask" "F.Paste")
			(net "M_I_CPU1_SA_CA<1>")
		)
		(pad "AY21" smd circle
			(at -15.830042 -5.219954 180)
			(size 0.450088 0.450088)
			(layers "F.Cu" "F.Mask" "F.Paste")
			(net "M_I_CPU1_SA_CA<2>")
		)
		(pad "AY22" smd circle
			(at -14.889988 -5.219954 180)
			(size 0.450088 0.450088)
			(layers "F.Cu" "F.Mask" "F.Paste")
			(net "PVDDCR_SOC_P1")
		)
		(pad "AY23" smd circle
			(at -13.949934 -5.219954 180)
			(size 0.450088 0.450088)
			(layers "F.Cu" "F.Mask" "F.Paste")
			(net "GND")
		)
		(pad "AY24" smd circle
			(at -13.00988 -5.219954 180)
			(size 0.450088 0.450088)
			(layers "F.Cu" "F.Mask" "F.Paste")
			(net "PVDDCR_SOC_P1")
		)
		(pad "AY25" smd circle
			(at -12.07008 -5.219954 180)
			(size 0.450088 0.450088)
			(layers "F.Cu" "F.Mask" "F.Paste")
			(net "GND")
		)
		(pad "AY26" smd circle
			(at -11.130026 -5.219954 180)
			(size 0.450088 0.450088)
			(layers "F.Cu" "F.Mask" "F.Paste")
			(net "PVDDCR_SOC_P1")
		)
		(pad "AY27" smd circle
			(at -10.189972 -5.219954 180)
			(size 0.450088 0.450088)
			(layers "F.Cu" "F.Mask" "F.Paste")
			(net "GND")
		)
		(pad "AY28" smd circle
			(at -9.249918 -5.219954 180)
			(size 0.450088 0.450088)
			(layers "F.Cu" "F.Mask" "F.Paste")
			(net "PVDDCR_SOC_P1")
		)
		(pad "AY48" smd circle
			(at 9.549892 -5.219954 180)
			(size 0.450088 0.450088)
			(layers "F.Cu" "F.Mask" "F.Paste")
			(net "GND")
		)
		(pad "AY49" smd circle
			(at 10.489946 -5.219954 180)
			(size 0.450088 0.450088)
			(layers "F.Cu" "F.Mask" "F.Paste")
			(net "PVDDCR_SOC_P1")
		)
		(pad "AY50" smd circle
			(at 11.43 -5.219954 180)
			(size 0.450088 0.450088)
			(layers "F.Cu" "F.Mask" "F.Paste")
			(net "GND")
		)
		(pad "AY51" smd circle
			(at 12.370054 -5.219954 180)
			(size 0.450088 0.450088)
			(layers "F.Cu" "F.Mask" "F.Paste")
			(net "PVDD18_S5_P1")
		)
		(pad "AY52" smd circle
			(at 13.310108 -5.219954 180)
			(size 0.450088 0.450088)
			(layers "F.Cu" "F.Mask" "F.Paste")
			(net "GND")
		)
		(pad "AY53" smd circle
			(at 14.249908 -5.219954 180)
			(size 0.450088 0.450088)
			(layers "F.Cu" "F.Mask" "F.Paste")
			(net "PVDD18_S5_P1")
		)
		(pad "AY54" smd circle
			(at 15.189962 -5.219954 180)
			(size 0.450088 0.450088)
			(layers "F.Cu" "F.Mask" "F.Paste")
			(net "GND")
		)
		(pad "AY55" smd circle
			(at 16.130016 -5.219954 180)
			(size 0.450088 0.450088)
			(layers "F.Cu" "F.Mask" "F.Paste")
			(net "M_C_CPU1_SA_CA<2>")
		)
		(pad "AY56" smd circle
			(at 17.07007 -5.219954 180)
			(size 0.450088 0.450088)
			(layers "F.Cu" "F.Mask" "F.Paste")
			(net "M_C_CPU1_SA_CA<1>")
		)
		(pad "AY57" smd circle
			(at 18.010124 -5.219954 180)
			(size 0.450088 0.450088)
			(layers "F.Cu" "F.Mask" "F.Paste")
			(net "GND")
		)
		(pad "AY58" smd circle
			(at 18.949924 -5.219954 180)
			(size 0.450088 0.450088)
			(layers "F.Cu" "F.Mask" "F.Paste")
			(net "M_D_CPU1_SA_CA<2>")
		)
		(pad "AY59" smd circle
			(at 19.889978 -5.219954 180)
			(size 0.450088 0.450088)
			(layers "F.Cu" "F.Mask" "F.Paste")
			(net "GND")
		)
		(pad "AY60" smd circle
			(at 20.830032 -5.219954 180)
			(size 0.450088 0.450088)
			(layers "F.Cu" "F.Mask" "F.Paste")
			(net "M_D_CPU1_SA_CA<1>")
		)
		(pad "AY61" smd circle
			(at 21.770086 -5.219954 180)
			(size 0.450088 0.450088)
			(layers "F.Cu" "F.Mask" "F.Paste")
			(net "GND")
		)
		(pad "AY62" smd circle
			(at 22.709886 -5.219954 180)
			(size 0.450088 0.450088)
			(layers "F.Cu" "F.Mask" "F.Paste")
			(net "M_B_CPU1_SA_CA<2>")
		)
		(pad "AY63" smd circle
			(at 23.64994 -5.219954 180)
			(size 0.450088 0.450088)
			(layers "F.Cu" "F.Mask" "F.Paste")
			(net "M_B_CPU1_SA_CA<1>")
		)
		(pad "AY64" smd circle
			(at 24.589994 -5.219954 180)
			(size 0.450088 0.450088)
			(layers "F.Cu" "F.Mask" "F.Paste")
			(net "GND")
		)
		(pad "AY65" smd circle
			(at 25.530048 -5.219954 180)
			(size 0.450088 0.450088)
			(layers "F.Cu" "F.Mask" "F.Paste")
			(net "M_F_CPU1_SA_CA<2>")
		)
		(pad "AY66" smd circle
			(at 26.470102 -5.219954 180)
			(size 0.450088 0.450088)
			(layers "F.Cu" "F.Mask" "F.Paste")
			(net "GND")
		)
		(pad "AY67" smd circle
			(at 27.409902 -5.219954 180)
			(size 0.450088 0.450088)
			(layers "F.Cu" "F.Mask" "F.Paste")
			(net "M_F_CPU1_SA_CA<1>")
		)
		(pad "AY68" smd circle
			(at 28.349956 -5.219954 180)
			(size 0.450088 0.450088)
			(layers "F.Cu" "F.Mask" "F.Paste")
			(net "GND")
		)
		(pad "AY69" smd circle
			(at 29.29001 -5.219954 180)
			(size 0.450088 0.450088)
			(layers "F.Cu" "F.Mask" "F.Paste")
			(net "M_E_CPU1_SA_CA<2>")
		)
		(pad "AY70" smd circle
			(at 30.230064 -5.219954 180)
			(size 0.450088 0.450088)
			(layers "F.Cu" "F.Mask" "F.Paste")
			(net "M_E_CPU1_SA_CA<1>")
		)
		(pad "AY71" smd circle
			(at 31.170118 -5.219954 180)
			(size 0.450088 0.450088)
			(layers "F.Cu" "F.Mask" "F.Paste")
			(net "GND")
		)
		(pad "AY72" smd circle
			(at 32.109918 -5.219954 180)
			(size 0.450088 0.450088)
			(layers "F.Cu" "F.Mask" "F.Paste")
			(net "M_A_CPU1_SA_CA<2>")
		)
		(pad "AY73" smd circle
			(at 33.049972 -5.219954 180)
			(size 0.450088 0.450088)
			(layers "F.Cu" "F.Mask" "F.Paste")
			(net "GND")
		)
		(pad "AY74" smd circle
			(at 33.990026 -5.219954 180)
			(size 0.450088 0.450088)
			(layers "F.Cu" "F.Mask" "F.Paste")
			(net "M_A_CPU1_SA_CA<1>")
		)
		(pad "B3" smd circle
			(at -32.749998 -35.999928 180)
			(size 0.450088 0.450088)
			(layers "F.Cu" "F.Mask" "F.Paste")
			(net "VSENSE_PVDDCR_SOC_P1_DP")
		)
		(pad "B4" smd circle
			(at -31.809944 -35.999928 180)
			(size 0.450088 0.450088)
			(layers "F.Cu" "F.Mask" "F.Paste")
			(net "Net_2099")
		)
		(pad "B5" smd circle
			(at -30.86989 -35.999928 180)
			(size 0.450088 0.450088)
			(layers "F.Cu" "F.Mask" "F.Paste")
			(net "PVDDCR_SOC_P1")
		)
		(pad "B6" smd circle
			(at -29.93009 -35.999928 180)
			(size 0.450088 0.450088)
			(layers "F.Cu" "F.Mask" "F.Paste")
			(net "CLK_100M_CPU1_CLK02_R_DP")
		)
		(pad "B7" smd circle
			(at -28.990036 -35.999928 180)
			(size 0.450088 0.450088)
			(layers "F.Cu" "F.Mask" "F.Paste")
			(net "GND")
		)
		(pad "B8" smd circle
			(at -28.049982 -35.999928 180)
			(size 0.450088 0.450088)
			(layers "F.Cu" "F.Mask" "F.Paste")
			(net "GND")
		)
		(pad "B9" smd circle
			(at -27.109928 -35.999928 180)
			(size 0.450088 0.450088)
			(layers "F.Cu" "F.Mask" "F.Paste")
			(net "CLK_100M_CPU1_CLK05_R_DP")
		)
		(pad "B10" smd circle
			(at -26.170128 -35.999928 180)
			(size 0.450088 0.450088)
			(layers "F.Cu" "F.Mask" "F.Paste")
			(net "GND")
		)
		(pad "B11" smd circle
			(at -25.230074 -35.999928 180)
			(size 0.450088 0.450088)
			(layers "F.Cu" "F.Mask" "F.Paste")
			(net "GND")
		)
		(pad "B12" smd circle
			(at -24.29002 -35.999928 180)
			(size 0.450088 0.450088)
			(layers "F.Cu" "F.Mask" "F.Paste")
			(net "CLK_100M_CPU1_CLK04_R_DP")
		)
		(pad "B13" smd circle
			(at -23.349966 -35.999928 180)
			(size 0.450088 0.450088)
			(layers "F.Cu" "F.Mask" "F.Paste")
			(net "GND")
		)
		(pad "B14" smd circle
			(at -22.409912 -35.999928 180)
			(size 0.450088 0.450088)
			(layers "F.Cu" "F.Mask" "F.Paste")
			(net "SMB_CPU1_SEC_SCL")
		)
		(pad "B15" smd circle
			(at -21.470112 -35.999928 180)
			(size 0.450088 0.450088)
			(layers "F.Cu" "F.Mask" "F.Paste")
			(net "Net_2101")
		)
		(pad "B16" smd circle
			(at -20.530058 -35.999928 180)
			(size 0.450088 0.450088)
			(layers "F.Cu" "F.Mask" "F.Paste")
			(net "Net_2083")
		)
		(pad "B17" smd circle
			(at -19.590004 -35.999928 180)
			(size 0.450088 0.450088)
			(layers "F.Cu" "F.Mask" "F.Paste")
			(net "JTAG_CPU1_TCK")
		)
		(pad "B18" smd circle
			(at -18.64995 -35.999928 180)
			(size 0.450088 0.450088)
			(layers "F.Cu" "F.Mask" "F.Paste")
			(net "GND")
		)
		(pad "B19" smd circle
			(at -17.709896 -35.999928 180)
			(size 0.450088 0.450088)
			(layers "F.Cu" "F.Mask" "F.Paste")
			(net "PVDDCR_CPU0_P1")
		)
		(pad "B20" smd circle
			(at -16.770096 -35.999928 180)
			(size 0.450088 0.450088)
			(layers "F.Cu" "F.Mask" "F.Paste")
			(net "PVDDCR_CPU0_P1")
		)
		(pad "B21" smd circle
			(at -15.830042 -35.999928 180)
			(size 0.450088 0.450088)
			(layers "F.Cu" "F.Mask" "F.Paste")
			(net "SVID_PVDDCR_CPU0_P1_SVTO")
		)
		(pad "B22" smd circle
			(at -14.889988 -35.999928 180)
			(size 0.450088 0.450088)
			(layers "F.Cu" "F.Mask" "F.Paste")
			(net "PVDDCR_CPU0_P1")
		)
		(pad "B23" smd circle
			(at -13.949934 -35.999928 180)
			(size 0.450088 0.450088)
			(layers "F.Cu" "F.Mask" "F.Paste")
			(net "PVDDCR_CPU0_P1")
		)
		(pad "B24" smd circle
			(at -13.00988 -35.999928 180)
			(size 0.450088 0.450088)
			(layers "F.Cu" "F.Mask" "F.Paste")
			(net "GND")
		)
		(pad "B25" smd circle
			(at -12.07008 -35.999928 180)
			(size 0.450088 0.450088)
			(layers "F.Cu" "F.Mask" "F.Paste")
			(net "PVDDCR_CPU0_P1")
		)
		(pad "B26" smd circle
			(at -11.130026 -35.999928 180)
			(size 0.450088 0.450088)
			(layers "F.Cu" "F.Mask" "F.Paste")
			(net "PVDDCR_CPU0_P1")
		)
		(pad "B27" smd circle
			(at -10.189972 -35.999928 180)
			(size 0.450088 0.450088)
			(layers "F.Cu" "F.Mask" "F.Paste")
			(net "GND")
		)
		(pad "B28" smd circle
			(at -9.249918 -35.999928 180)
			(size 0.450088 0.450088)
			(layers "F.Cu" "F.Mask" "F.Paste")
			(net "PVDDCR_CPU0_P1")
		)
		(pad "B29" smd circle
			(at -8.310118 -35.999928 180)
			(size 0.450088 0.450088)
			(layers "F.Cu" "F.Mask" "F.Paste")
			(net "PVDDCR_CPU0_P1")
		)
		(pad "B30" smd circle
			(at -7.370064 -35.999928 180)
			(size 0.450088 0.450088)
			(layers "F.Cu" "F.Mask" "F.Paste")
			(net "GND")
		)
		(pad "B31" smd circle
			(at -6.43001 -35.999928 180)
			(size 0.450088 0.450088)
			(layers "F.Cu" "F.Mask" "F.Paste")
			(net "PVDDCR_CPU0_P1")
		)
		(pad "B32" smd circle
			(at -5.489956 -35.999928 180)
			(size 0.450088 0.450088)
			(layers "F.Cu" "F.Mask" "F.Paste")
			(net "PVDDCR_CPU0_P1")
		)
		(pad "B33" smd circle
			(at -4.549902 -35.999928 180)
			(size 0.450088 0.450088)
			(layers "F.Cu" "F.Mask" "F.Paste")
			(net "GND")
		)
		(pad "B34" smd circle
			(at -3.610102 -35.999928 180)
			(size 0.450088 0.450088)
			(layers "F.Cu" "F.Mask" "F.Paste")
			(net "PVDDCR_CPU0_P1")
		)
		(pad "B35" smd circle
			(at -2.670048 -35.999928 180)
			(size 0.450088 0.450088)
			(layers "F.Cu" "F.Mask" "F.Paste")
			(net "PVDDCR_CPU0_P1")
		)
		(pad "B36" smd circle
			(at -1.729994 -35.999928 180)
			(size 0.450088 0.450088)
			(layers "F.Cu" "F.Mask" "F.Paste")
			(net "Net_2177")
		)
		(pad "B37" smd circle
			(at -0.78994 -35.999928 180)
			(size 0.450088 0.450088)
			(layers "F.Cu" "F.Mask" "F.Paste")
			(net "GND")
		)
		(pad "B39" smd circle
			(at 1.089914 -35.999928 180)
			(size 0.450088 0.450088)
			(layers "F.Cu" "F.Mask" "F.Paste")
			(net "GND")
		)
		(pad "B40" smd circle
			(at 2.029968 -35.999928 180)
			(size 0.450088 0.450088)
			(layers "F.Cu" "F.Mask" "F.Paste")
			(net "Net_2135")
		)
		(pad "B41" smd circle
			(at 2.970022 -35.999928 180)
			(size 0.450088 0.450088)
			(layers "F.Cu" "F.Mask" "F.Paste")
			(net "PVDDCR_CPU0_P1")
		)
		(pad "B42" smd circle
			(at 3.910076 -35.999928 180)
			(size 0.450088 0.450088)
			(layers "F.Cu" "F.Mask" "F.Paste")
			(net "PVDDCR_CPU0_P1")
		)
		(pad "B43" smd circle
			(at 4.849876 -35.999928 180)
			(size 0.450088 0.450088)
			(layers "F.Cu" "F.Mask" "F.Paste")
			(net "GND")
		)
		(pad "B44" smd circle
			(at 5.78993 -35.999928 180)
			(size 0.450088 0.450088)
			(layers "F.Cu" "F.Mask" "F.Paste")
			(net "PVDDCR_CPU0_P1")
		)
		(pad "B45" smd circle
			(at 6.729984 -35.999928 180)
			(size 0.450088 0.450088)
			(layers "F.Cu" "F.Mask" "F.Paste")
			(net "PVDDCR_CPU0_P1")
		)
		(pad "B46" smd circle
			(at 7.670038 -35.999928 180)
			(size 0.450088 0.450088)
			(layers "F.Cu" "F.Mask" "F.Paste")
			(net "GND")
		)
		(pad "B47" smd circle
			(at 8.610092 -35.999928 180)
			(size 0.450088 0.450088)
			(layers "F.Cu" "F.Mask" "F.Paste")
			(net "PVDDCR_CPU0_P1")
		)
		(pad "B48" smd circle
			(at 9.549892 -35.999928 180)
			(size 0.450088 0.450088)
			(layers "F.Cu" "F.Mask" "F.Paste")
			(net "PVDDCR_CPU0_P1")
		)
		(pad "B49" smd circle
			(at 10.489946 -35.999928 180)
			(size 0.450088 0.450088)
			(layers "F.Cu" "F.Mask" "F.Paste")
			(net "GND")
		)
		(pad "B50" smd circle
			(at 11.43 -35.999928 180)
			(size 0.450088 0.450088)
			(layers "F.Cu" "F.Mask" "F.Paste")
			(net "PVDDCR_CPU0_P1")
		)
		(pad "B51" smd circle
			(at 12.370054 -35.999928 180)
			(size 0.450088 0.450088)
			(layers "F.Cu" "F.Mask" "F.Paste")
			(net "PVDDCR_CPU0_P1")
		)
		(pad "B52" smd circle
			(at 13.310108 -35.999928 180)
			(size 0.450088 0.450088)
			(layers "F.Cu" "F.Mask" "F.Paste")
			(net "GND")
		)
		(pad "B53" smd circle
			(at 14.249908 -35.999928 180)
			(size 0.450088 0.450088)
			(layers "F.Cu" "F.Mask" "F.Paste")
			(net "PVDDCR_CPU0_P1")
		)
		(pad "B54" smd circle
			(at 15.189962 -35.999928 180)
			(size 0.450088 0.450088)
			(layers "F.Cu" "F.Mask" "F.Paste")
			(net "PVDDCR_CPU0_P1")
		)
		(pad "B55" smd circle
			(at 16.130016 -35.999928 180)
			(size 0.450088 0.450088)
			(layers "F.Cu" "F.Mask" "F.Paste")
			(net "GND")
		)
		(pad "B56" smd circle
			(at 17.07007 -35.999928 180)
			(size 0.450088 0.450088)
			(layers "F.Cu" "F.Mask" "F.Paste")
			(net "PVDDCR_CPU0_P1")
		)
		(pad "B57" smd circle
			(at 18.010124 -35.999928 180)
			(size 0.450088 0.450088)
			(layers "F.Cu" "F.Mask" "F.Paste")
			(net "PVDDCR_CPU0_P1")
		)
		(pad "B58" smd circle
			(at 18.949924 -35.999928 180)
			(size 0.450088 0.450088)
			(layers "F.Cu" "F.Mask" "F.Paste")
			(net "TP_CPU1_TEST47_IOD0")
		)
		(pad "B59" smd circle
			(at 19.889978 -35.999928 180)
			(size 0.450088 0.450088)
			(layers "F.Cu" "F.Mask" "F.Paste")
			(net "GND")
		)
		(pad "B60" smd circle
			(at 20.830032 -35.999928 180)
			(size 0.450088 0.450088)
			(layers "F.Cu" "F.Mask" "F.Paste")
			(net "TP_CPU1_TEST47_CCD0")
		)
		(pad "B61" smd circle
			(at 21.770086 -35.999928 180)
			(size 0.450088 0.450088)
			(layers "F.Cu" "F.Mask" "F.Paste")
			(net "TP_CPU1_TEST50_IOD")
		)
		(pad "B62" smd circle
			(at 22.709886 -35.999928 180)
			(size 0.450088 0.450088)
			(layers "F.Cu" "F.Mask" "F.Paste")
			(net "GND")
		)
		(pad "B63" smd circle
			(at 23.64994 -35.999928 180)
			(size 0.450088 0.450088)
			(layers "F.Cu" "F.Mask" "F.Paste")
			(net "CPU1_FORCE_SELFREFRESH")
		)
		(pad "B64" smd circle
			(at 24.589994 -35.999928 180)
			(size 0.450088 0.450088)
			(layers "F.Cu" "F.Mask" "F.Paste")
			(net "CPU1_NV_SAVE_N")
		)
		(pad "B65" smd circle
			(at 25.530048 -35.999928 180)
			(size 0.450088 0.450088)
			(layers "F.Cu" "F.Mask" "F.Paste")
			(net "GND")
		)
		(pad "B66" smd circle
			(at 26.470102 -35.999928 180)
			(size 0.450088 0.450088)
			(layers "F.Cu" "F.Mask" "F.Paste")
			(net "PRSNT_CPU1_N")
		)
		(pad "B67" smd circle
			(at 27.409902 -35.999928 180)
			(size 0.450088 0.450088)
			(layers "F.Cu" "F.Mask" "F.Paste")
			(net "RST_CPU1_RESETL_N")
		)
		(pad "B68" smd circle
			(at 28.349956 -35.999928 180)
			(size 0.450088 0.450088)
			(layers "F.Cu" "F.Mask" "F.Paste")
			(net "GND")
		)
		(pad "B69" smd circle
			(at 29.29001 -35.999928 180)
			(size 0.450088 0.450088)
			(layers "F.Cu" "F.Mask" "F.Paste")
			(net "CPU1_CORETYPE1")
		)
		(pad "B70" smd circle
			(at 30.230064 -35.999928 180)
			(size 0.450088 0.450088)
			(layers "F.Cu" "F.Mask" "F.Paste")
			(net "GND")
		)
		(pad "B71" smd circle
			(at 31.170118 -35.999928 180)
			(size 0.450088 0.450088)
			(layers "F.Cu" "F.Mask" "F.Paste")
			(net "I3C_0_SPD_DDRAF_CPU1_R_SDA")
		)
		(pad "B72" smd circle
			(at 32.109918 -35.999928 180)
			(size 0.450088 0.450088)
			(layers "F.Cu" "F.Mask" "F.Paste")
			(net "Net_2097")
		)
		(pad "B73" smd circle
			(at 33.049972 -35.999928 180)
			(size 0.450088 0.450088)
			(layers "F.Cu" "F.Mask" "F.Paste")
			(net "VSENSE_PVDD18_S5_P1_DN")
		)
	)
)
